# S9S_MB_2U (Grand Teton) — schematic netlist excerpt (pin names and nets, part order shuffled) for the footprints in the layout excerpt that follows; sources: Cadence DE-HDL packaged netlist, KiCad conversion of 03242023_DA0F0TMBIJ0_F0T_Motherboard_J_brd_V01_OCP.brd

R197  Q_RES  301 1% CHIP  pkg 0402LF  page 123 : A = PVNN_TERM_CPU0 ; B = H_CPU0_NMI_LVC1_N
C82  Q_CAP  10UF 16V 10% X6S  pkg C0805  page 110 : A = P12V_S3_AUX_CPU1_NVDIMM ; B = GND
R2205  Q_RES  2.2K 5% EMPTY  pkg 0402LF  page 231 : A = P3V3_AUX ; B = SMB_PCIE0_3V3AUX_SDA

(kicad_pcb
	(version 20260206)
	(generator "pcbnew")
	(generator_version "10.0")
	(general
		(thickness 1.6)
		(legacy_teardrops no)
	)
	(paper "A4")
	(title_block
		(title "03242023_DA0F0TMBIJ0_F0T_Motherboard_J_brd_V01_OCP.brd")
		(comment 1 "Grand Teton / footprints 5533-5535 of 6105")
	)
	(layers
		(0 "F.Cu" signal "TOP")
		(4 "In1.Cu" signal "GND")
		(6 "In2.Cu" signal "IN1")
		(8 "In3.Cu" signal "GND1")
		(10 "In4.Cu" signal "IN2")
		(12 "In5.Cu" signal "GND2")
		(14 "In6.Cu" signal "IN3")
		(16 "In7.Cu" signal "GND3")
		(18 "In8.Cu" signal "VCC")
		(20 "In9.Cu" signal "VCC1")
		(22 "In10.Cu" signal "GND4")
		(24 "In11.Cu" signal "IN4")
		(26 "In12.Cu" signal "GND5")
		(28 "In13.Cu" signal "IN5")
		(30 "In14.Cu" signal "GND6")
		(32 "In15.Cu" signal "IN6")
		(34 "In16.Cu" signal "GND7")
		(2 "B.Cu" signal "BOTTOM")
		(9 "F.Adhes" user "F.Adhesive")
		(11 "B.Adhes" user "B.Adhesive")
		(13 "F.Paste" user "Package Geometry/Pastemask Top")
		(15 "B.Paste" user "Package Geometry/Pastemask Bottom")
		(5 "F.SilkS" user "Ref Des/Silkscreen Top")
		(7 "B.SilkS" user "Ref Des/Silkscreen Bottom")
		(1 "F.Mask" user "Board Geometry/Soldermask Top")
		(3 "B.Mask" user "Board Geometry/Soldermask Bottom")
		(17 "Dwgs.User" user "User.Drawings")
		(19 "Cmts.User" user "User.Comments")
		(21 "Eco1.User" user "User.Eco1")
		(23 "Eco2.User" user "User.Eco2")
		(25 "Edge.Cuts" user "Board Geometry/Outline")
		(27 "Margin" user)
		(31 "F.CrtYd" user "Package Geometry/Place Bound Top")
		(29 "B.CrtYd" user "Package Geometry/Place Bound Bottom")
		(35 "F.Fab" user "Ref Des/Assembly Top")
		(33 "B.Fab" user "Ref Des/Assembly Bottom")
	)
	(footprint ""
		(layer "B.Cu")
		(at 319.635378 -188.41339)
		(property "Reference" "R197"
			(at 0 0 0)
			(layer "B.SilkS")
			(hide yes)
			(effects
				(font
					(size 1.27 1.27)
				)
				(justify mirror)
			)
		)
		(property "Value" ""
			(at 0 0 0)
			(layer "B.Fab")
			(effects
				(font
					(size 1.27 1.27)
				)
				(justify mirror)
			)
		)
		(duplicate_pad_numbers_are_jumpers no)
		(fp_line
			(start -0.7874 -0.4064)
			(end -0.7874 0.4064)
			(stroke
				(width 0.1524)
				(type default)
			)
			(layer "B.SilkS")
		)
		(fp_line
			(start -0.7874 0.4064)
			(end 0.7874 0.4064)
			(stroke
				(width 0.1524)
				(type default)
			)
			(layer "B.SilkS")
		)
		(fp_line
			(start 0.7874 -0.4064)
			(end -0.7874 -0.4064)
			(stroke
				(width 0.1524)
				(type default)
			)
			(layer "B.SilkS")
		)
		(fp_line
			(start 0.7874 0.4064)
			(end 0.7874 -0.4064)
			(stroke
				(width 0.1524)
				(type default)
			)
			(layer "B.SilkS")
		)
		(fp_line
			(start -0.67945 -0.3048)
			(end -0.67945 0.3048)
			(stroke
				(width 0.1)
				(type default)
			)
			(layer "B.Fab")
		)
		(fp_line
			(start -0.67945 0.3048)
			(end -0.120396 0.3048)
			(stroke
				(width 0.1)
				(type default)
			)
			(layer "B.Fab")
		)
		(fp_line
			(start -0.12065 -0.3048)
			(end -0.67945 -0.3048)
			(stroke
				(width 0.1)
				(type default)
			)
			(layer "B.Fab")
		)
		(fp_line
			(start -0.12065 -0.2794)
			(end -0.12065 -0.3048)
			(stroke
				(width 0.1)
				(type default)
			)
			(layer "B.Fab")
		)
		(fp_line
			(start -0.120396 0.2794)
			(end 0.12065 0.2794)
			(stroke
				(width 0.1)
				(type default)
			)
			(layer "B.Fab")
		)
		(fp_line
			(start -0.120396 0.3048)
			(end -0.120396 0.2794)
			(stroke
				(width 0.1)
				(type default)
			)
			(layer "B.Fab")
		)
		(fp_line
			(start 0.12065 -0.305054)
			(end 0.12065 -0.2794)
			(stroke
				(width 0.1)
				(type default)
			)
			(layer "B.Fab")
		)
		(fp_line
			(start 0.12065 -0.2794)
			(end -0.12065 -0.2794)
			(stroke
				(width 0.1)
				(type default)
			)
			(layer "B.Fab")
		)
		(fp_line
			(start 0.12065 0.2794)
			(end 0.12065 0.3048)
			(stroke
				(width 0.1)
				(type default)
			)
			(layer "B.Fab")
		)
		(fp_line
			(start 0.12065 0.3048)
			(end 0.67945 0.3048)
			(stroke
				(width 0.1)
				(type default)
			)
			(layer "B.Fab")
		)
		(fp_line
			(start 0.67945 -0.305054)
			(end 0.12065 -0.305054)
			(stroke
				(width 0.1)
				(type default)
			)
			(layer "B.Fab")
		)
		(fp_line
			(start 0.67945 0.3048)
			(end 0.67945 -0.305054)
			(stroke
				(width 0.1)
				(type default)
			)
			(layer "B.Fab")
		)
		(pad "1" smd circle
			(at 0.40005 0 180)
			(size 0 0)
			(layers "B.Cu" "B.Mask" "B.Paste")
			(net "PVNN_TERM_CPU0")
		)
		(pad "2" smd circle
			(at -0.40005 0 180)
			(size 0 0)
			(layers "B.Cu" "B.Mask" "B.Paste")
			(net "H_CPU0_NMI_LVC1_N")
		)
	)
	(footprint ""
		(layer "B.Cu")
		(at 164.857938 -8.91794 -90)
		(property "Reference" "R2205"
			(at 0 0 90)
			(layer "B.SilkS")
			(hide yes)
			(effects
				(font
					(size 1.27 1.27)
				)
				(justify mirror)
			)
		)
		(property "Value" ""
			(at 0 0 90)
			(layer "B.Fab")
			(effects
				(font
					(size 1.27 1.27)
				)
				(justify mirror)
			)
		)
		(duplicate_pad_numbers_are_jumpers no)
		(fp_line
			(start -0.7874 0.4064)
			(end 0.7874 0.4064)
			(stroke
				(width 0.1524)
				(type default)
			)
			(layer "B.SilkS")
		)
		(fp_line
			(start 0.7874 0.4064)
			(end 0.7874 -0.4064)
			(stroke
				(width 0.1524)
				(type default)
			)
			(layer "B.SilkS")
		)
		(fp_line
			(start -0.7874 -0.4064)
			(end -0.7874 0.4064)
			(stroke
				(width 0.1524)
				(type default)
			)
			(layer "B.SilkS")
		)
		(fp_line
			(start 0.7874 -0.4064)
			(end -0.7874 -0.4064)
			(stroke
				(width 0.1524)
				(type default)
			)
			(layer "B.SilkS")
		)
		(fp_line
			(start -0.67945 0.3048)
			(end -0.120396 0.3048)
			(stroke
				(width 0.1)
				(type default)
			)
			(layer "B.Fab")
		)
		(fp_line
			(start -0.120396 0.3048)
			(end -0.120396 0.2794)
			(stroke
				(width 0.1)
				(type default)
			)
			(layer "B.Fab")
		)
		(fp_line
			(start 0.12065 0.3048)
			(end 0.67945 0.3048)
			(stroke
				(width 0.1)
				(type default)
			)
			(layer "B.Fab")
		)
		(fp_line
			(start 0.67945 0.3048)
			(end 0.67945 -0.305054)
			(stroke
				(width 0.1)
				(type default)
			)
			(layer "B.Fab")
		)
		(fp_line
			(start -0.120396 0.2794)
			(end 0.12065 0.2794)
			(stroke
				(width 0.1)
				(type default)
			)
			(layer "B.Fab")
		)
		(fp_line
			(start 0.12065 0.2794)
			(end 0.12065 0.3048)
			(stroke
				(width 0.1)
				(type default)
			)
			(layer "B.Fab")
		)
		(fp_line
			(start -0.12065 -0.2794)
			(end -0.12065 -0.3048)
			(stroke
				(width 0.1)
				(type default)
			)
			(layer "B.Fab")
		)
		(fp_line
			(start 0.12065 -0.2794)
			(end -0.12065 -0.2794)
			(stroke
				(width 0.1)
				(type default)
			)
			(layer "B.Fab")
		)
		(fp_line
			(start -0.67945 -0.3048)
			(end -0.67945 0.3048)
			(stroke
				(width 0.1)
				(type default)
			)
			(layer "B.Fab")
		)
		(fp_line
			(start -0.12065 -0.3048)
			(end -0.67945 -0.3048)
			(stroke
				(width 0.1)
				(type default)
			)
			(layer "B.Fab")
		)
		(fp_line
			(start 0.12065 -0.305054)
			(end 0.12065 -0.2794)
			(stroke
				(width 0.1)
				(type default)
			)
			(layer "B.Fab")
		)
		(fp_line
			(start 0.67945 -0.305054)
			(end 0.12065 -0.305054)
			(stroke
				(width 0.1)
				(type default)
			)
			(layer "B.Fab")
		)
		(pad "1" smd circle
			(at 0.40005 0 90)
			(size 0 0)
			(layers "B.Cu" "B.Mask" "B.Paste")
			(net "P3V3_AUX")
		)
		(pad "2" smd circle
			(at -0.40005 0 90)
			(size 0 0)
			(layers "B.Cu" "B.Mask" "B.Paste")
			(net "SMB_PCIE0_3V3AUX_SDA")
		)
	)
	(footprint ""
		(layer "B.Cu")
		(at 196.544946 -321.554856 -90)
		(property "Reference" "C82"
			(at 0 0 90)
			(layer "B.SilkS")
			(hide yes)
			(effects
				(font
					(size 1.27 1.27)
				)
				(justify mirror)
			)
		)
		(property "Value" ""
			(at 0 0 90)
			(layer "B.Fab")
			(effects
				(font
					(size 1.27 1.27)
				)
				(justify mirror)
			)
		)
		(duplicate_pad_numbers_are_jumpers no)
		(fp_line
			(start -1.524 0.762)
			(end 1.524 0.762)
			(stroke
				(width 0.1524)
				(type default)
			)
			(layer "B.SilkS")
		)
		(fp_line
			(start 1.524 0.762)
			(end 1.524 -0.762)
			(stroke
				(width 0.1524)
				(type default)
			)
			(layer "B.SilkS")
		)
		(fp_line
			(start -1.524 -0.762)
			(end -1.524 0.762)
			(stroke
				(width 0.1524)
				(type default)
			)
			(layer "B.SilkS")
		)
		(fp_line
			(start 1.524 -0.762)
			(end -1.524 -0.762)
			(stroke
				(width 0.1524)
				(type default)
			)
			(layer "B.SilkS")
		)
		(fp_line
			(start -1.1049 0.724916)
			(end -1.1049 -0.724916)
			(stroke
				(width 0.1)
				(type default)
			)
			(layer "B.Fab")
		)
		(fp_line
			(start 1.1049 0.724916)
			(end -1.1049 0.724916)
			(stroke
				(width 0.1)
				(type default)
			)
			(layer "B.Fab")
		)
		(fp_line
			(start -1.1049 -0.724916)
			(end 1.1049 -0.724916)
			(stroke
				(width 0.1)
				(type default)
			)
			(layer "B.Fab")
		)
		(fp_line
			(start 1.1049 -0.724916)
			(end 1.1049 0.724916)
			(stroke
				(width 0.1)
				(type default)
			)
			(layer "B.Fab")
		)
		(pad "1" smd rect
			(at 0.889 0 270)
			(size 1.016 1.27)
			(layers "B.Cu" "B.Mask" "B.Paste")
			(net "P12V_S3_AUX_CPU1_NVDIMM")
		)
		(pad "2" smd rect
			(at -0.889 0 270)
			(size 1.016 1.27)
			(layers "B.Cu" "B.Mask" "B.Paste")
			(net "GND")
		)
	)
)
